(kicad_pcb
	(version 20260206)
	(generator "pcbnew")
	(generator_version "10.0")
	(general
		(thickness 1.6)
		(legacy_teardrops no)
	)
	(paper "A4")
	(title_block
		(title "timecard-production-celestica-r4006 — R4006-B0001-02_R01.brd")
		(comment 1 "Time Appliance Project (Time Card) / footprints 358-365 of 1113")
	)
	(layers
		(0 "F.Cu" signal "TOP")
		(4 "In1.Cu" signal "L02_GND1")
		(6 "In2.Cu" signal "L03_SIG1")
		(8 "In3.Cu" signal "L04_GND2")
		(10 "In4.Cu" signal "L05_VCC1")
		(12 "In5.Cu" signal "L06_VCC2")
		(14 "In6.Cu" signal "L07_GND3")
		(16 "In7.Cu" signal "L08_SIG2")
		(18 "In8.Cu" signal "L09_GND4")
		(2 "B.Cu" signal "BOTTOM")
		(9 "F.Adhes" user "F.Adhesive")
		(11 "B.Adhes" user "B.Adhesive")
		(13 "F.Paste" user "Package Geometry/Pastemask Top")
		(15 "B.Paste" user "Package Geometry/Pastemask Bottom")
		(5 "F.SilkS" user "Ref Des/Silkscreen Top")
		(7 "B.SilkS" user "Ref Des/Silkscreen Bottom")
		(1 "F.Mask" user "Board Geometry/Soldermask Top")
		(3 "B.Mask" user "Board Geometry/Soldermask Bottom")
		(17 "Dwgs.User" user "User.Drawings")
		(19 "Cmts.User" user "User.Comments")
		(21 "Eco1.User" user "User.Eco1")
		(23 "Eco2.User" user "User.Eco2")
		(25 "Edge.Cuts" user "Board Geometry/Outline")
		(27 "Margin" user)
		(31 "F.CrtYd" user "Package Geometry/Place Bound Top")
		(29 "B.CrtYd" user "Package Geometry/Place Bound Bottom")
		(35 "F.Fab" user "Ref Des/Assembly Top")
		(33 "B.Fab" user "Ref Des/Assembly Bottom")
	)
	(footprint ""
		(layer "F.Cu")
		(at 132.334 -43.815)
		(property "Reference" "L12"
			(at -1.0795 -1.23063 0)
			(unlocked yes)
			(layer "F.SilkS")
			(effects
				(font
					(size 0.7874 0.5842)
					(thickness 0.1524)
				)
				(justify left)
			)
		)
		(property "Value" "VAL*"
			(at -0.9398 3.70967 0)
			(unlocked yes)
			(layer "F.Fab")
			(hide yes)
			(effects
				(font
					(size 0.7874 0.5842)
					(thickness 0.1524)
				)
				(justify left)
			)
		)
		(property "Tolerance" "TOL*"
			(at -0.9906 5.00507 0)
			(unlocked yes)
			(layer "Cmts.User")
			(hide yes)
			(effects
				(font
					(size 0.7874 0.5842)
					(thickness 0.1524)
				)
				(justify left)
			)
		)
		(property "User Part Number" "PARTNUM*"
			(at -2.54 2.46507 0)
			(unlocked yes)
			(layer "Cmts.User")
			(hide yes)
			(effects
				(font
					(size 0.7874 0.5842)
					(thickness 0.1524)
				)
				(justify left)
			)
		)
		(property "Device Type" "FERRITEBEAD-G191-10100-01,120OA"
			(at -0.9906 1.22047 0)
			(unlocked yes)
			(layer "F.Fab")
			(hide yes)
			(effects
				(font
					(size 0.7874 0.5842)
					(thickness 0.1524)
				)
				(justify left)
			)
		)
		(duplicate_pad_numbers_are_jumpers no)
		(fp_line
			(start -1.3208 -0.7112)
			(end 1.3208 -0.7112)
			(stroke
				(width 0.1)
				(type default)
			)
			(layer "F.SilkS")
		)
		(fp_line
			(start -1.3208 0.7112)
			(end -1.3208 -0.7112)
			(stroke
				(width 0.1)
				(type default)
			)
			(layer "F.SilkS")
		)
		(fp_line
			(start 1.3208 -0.7112)
			(end 1.3208 0.7112)
			(stroke
				(width 0.1)
				(type default)
			)
			(layer "F.SilkS")
		)
		(fp_line
			(start 1.3208 0.7112)
			(end -1.3208 0.7112)
			(stroke
				(width 0.1)
				(type default)
			)
			(layer "F.SilkS")
		)
		(fp_rect
			(start -1.3208 0.7112)
			(end 1.3208 -0.7112)
			(stroke
				(width 0)
				(type default)
			)
			(fill no)
			(layer "F.CrtYd")
		)
		(fp_line
			(start -0.8128 -0.4572)
			(end 0.8128 -0.4572)
			(stroke
				(width 0.1)
				(type default)
			)
			(layer "F.Fab")
		)
		(fp_line
			(start -0.8128 0.4572)
			(end -0.8128 -0.4572)
			(stroke
				(width 0.1)
				(type default)
			)
			(layer "F.Fab")
		)
		(fp_line
			(start 0.8128 -0.4572)
			(end 0.8128 0.4572)
			(stroke
				(width 0.1)
				(type default)
			)
			(layer "F.Fab")
		)
		(fp_line
			(start 0.8128 0.4572)
			(end -0.8128 0.4572)
			(stroke
				(width 0.1)
				(type default)
			)
			(layer "F.Fab")
		)
		(pad "1" smd rect
			(at -0.6858 0)
			(size 0.762 0.8636)
			(layers "F.Cu" "F.Mask" "F.Paste")
			(net "XP1R0V_FPGA_VCCINT")
		)
		(pad "2" smd rect
			(at 0.6858 0)
			(size 0.762 0.8636)
			(layers "F.Cu" "F.Mask" "F.Paste")
			(net "XP1R0V_FPGA")
		)
		(zone
			(layer "F.Cu")
			(hatch none 0.5)
			(connect_pads
				(clearance 0)
			)
			(min_thickness 0.25)
			(keepout
				(tracks allowed)
				(vias not_allowed)
				(pads allowed)
				(copperpour not_allowed)
				(footprints allowed)
			)
			(placement
				(enabled no)
				(sheetname "")
			)
			(fill
				(thermal_gap 0.5)
				(thermal_bridge_width 0.5)
				(island_removal_mode 0)
			)
			(polygon
				(pts
					(xy 132.1816 -43.3578) (xy 132.4864 -43.3578) (xy 132.4864 -44.2722) (xy 132.1816 -44.2722)
				)
			)
		)
		(zone
			(layer "F.Cu")
			(hatch none 0.5)
			(connect_pads
				(clearance 0)
			)
			(min_thickness 0.25)
			(keepout
				(tracks not_allowed)
				(vias allowed)
				(pads allowed)
				(copperpour not_allowed)
				(footprints allowed)
			)
			(placement
				(enabled no)
				(sheetname "")
			)
			(fill
				(thermal_gap 0.5)
				(thermal_bridge_width 0.5)
				(island_removal_mode 0)
			)
			(polygon
				(pts
					(xy 132.1816 -43.3578) (xy 132.4864 -43.3578) (xy 132.4864 -44.2722) (xy 132.1816 -44.2722)
				)
			)
		)
	)
	(footprint ""
		(layer "F.Cu")
		(at 57.404 -126.873)
		(property "Reference" "SP57"
			(at 0 0 0)
			(layer "F.SilkS")
			(hide yes)
			(effects
				(font
					(size 1.27 1.27)
				)
			)
		)
		(property "Value" ""
			(at 0 0 0)
			(layer "F.Fab")
			(effects
				(font
					(size 1.27 1.27)
				)
			)
		)
		(duplicate_pad_numbers_are_jumpers no)
	)
	(footprint ""
		(layer "F.Cu")
		(at 48.26 -126.238)
		(property "Reference" "SP26"
			(at 0 0 0)
			(layer "F.SilkS")
			(hide yes)
			(effects
				(font
					(size 1.27 1.27)
				)
			)
		)
		(property "Value" ""
			(at 0 0 0)
			(layer "F.Fab")
			(effects
				(font
					(size 1.27 1.27)
				)
			)
		)
		(duplicate_pad_numbers_are_jumpers no)
	)
	(footprint ""
		(layer "F.Cu")
		(at 57.47512 -82.9564 90)
		(property "Reference" "R406"
			(at 0.2286 1.11125 90)
			(unlocked yes)
			(layer "F.SilkS")
			(effects
				(font
					(size 0.7874 0.5842)
					(thickness 0.1524)
				)
			)
		)
		(property "Value" "VAL*"
			(at 0.02032 2.13233 90)
			(unlocked yes)
			(layer "F.Fab")
			(hide yes)
			(effects
				(font
					(size 0.7874 0.5842)
					(thickness 0.1524)
				)
			)
		)
		(property "Device Type" "RESISTOR-G155-133R0-01,33OHM,1%"
			(at 0.008382 1.210564 90)
			(unlocked yes)
			(layer "F.Fab")
			(hide yes)
			(effects
				(font
					(size 0.7874 0.5842)
					(thickness 0.1524)
				)
			)
		)
		(property "User Part Number" "PARTNUM*"
			(at 0.02032 4.024884 90)
			(unlocked yes)
			(layer "Cmts.User")
			(hide yes)
			(effects
				(font
					(size 0.7874 0.5842)
					(thickness 0.1524)
				)
			)
		)
		(property "Tolerance" "TOL*"
			(at 0.044704 3.05435 90)
			(unlocked yes)
			(layer "Cmts.User")
			(hide yes)
			(effects
				(font
					(size 0.7874 0.5842)
					(thickness 0.1524)
				)
			)
		)
		(duplicate_pad_numbers_are_jumpers no)
		(fp_line
			(start 1.143 -0.5588)
			(end -1.143 -0.5588)
			(stroke
				(width 0.1)
				(type default)
			)
			(layer "F.SilkS")
		)
		(fp_line
			(start -1.143 -0.5588)
			(end -1.143 0.5588)
			(stroke
				(width 0.1)
				(type default)
			)
			(layer "F.SilkS")
		)
		(fp_line
			(start 1.143 0.5588)
			(end 1.143 -0.5588)
			(stroke
				(width 0.1)
				(type default)
			)
			(layer "F.SilkS")
		)
		(fp_line
			(start -1.143 0.5588)
			(end 1.143 0.5588)
			(stroke
				(width 0.1)
				(type default)
			)
			(layer "F.SilkS")
		)
		(fp_rect
			(start -1.143 0.5588)
			(end 1.143 -0.5588)
			(stroke
				(width 0)
				(type default)
			)
			(fill no)
			(layer "F.CrtYd")
		)
		(fp_line
			(start 0.508 -0.3048)
			(end -0.508 -0.3048)
			(stroke
				(width 0.1)
				(type default)
			)
			(layer "F.Fab")
		)
		(fp_line
			(start -0.508 -0.3048)
			(end -0.508 0.3048)
			(stroke
				(width 0.1)
				(type default)
			)
			(layer "F.Fab")
		)
		(fp_line
			(start 0.508 0.3048)
			(end 0.508 -0.3048)
			(stroke
				(width 0.1)
				(type default)
			)
			(layer "F.Fab")
		)
		(fp_line
			(start -0.508 0.3048)
			(end 0.508 0.3048)
			(stroke
				(width 0.1)
				(type default)
			)
			(layer "F.Fab")
		)
		(pad "1" smd rect
			(at -0.5334 0 90)
			(size 0.7112 0.6096)
			(layers "F.Cu" "F.Mask" "F.Paste")
			(net "LM75B_I2C_SDA")
		)
		(pad "2" smd rect
			(at 0.5334 0 90)
			(size 0.7112 0.6096)
			(layers "F.Cu" "F.Mask" "F.Paste")
			(net "R_LM75B_2_I2C_SDA")
		)
		(zone
			(layer "F.Cu")
			(hatch none 0.5)
			(connect_pads
				(clearance 0)
			)
			(min_thickness 0.25)
			(keepout
				(tracks allowed)
				(vias not_allowed)
				(pads allowed)
				(copperpour not_allowed)
				(footprints allowed)
			)
			(placement
				(enabled no)
				(sheetname "")
			)
			(fill
				(thermal_gap 0.5)
				(thermal_bridge_width 0.5)
				(island_removal_mode 0)
			)
			(polygon
				(pts
					(xy 57.77992 -82.8802) (xy 57.77992 -83.0326) (xy 57.17032 -83.0326) (xy 57.17032 -82.8802)
				)
			)
		)
		(zone
			(layer "F.Cu")
			(hatch none 0.5)
			(connect_pads
				(clearance 0)
			)
			(min_thickness 0.25)
			(keepout
				(tracks not_allowed)
				(vias allowed)
				(pads allowed)
				(copperpour not_allowed)
				(footprints allowed)
			)
			(placement
				(enabled no)
				(sheetname "")
			)
			(fill
				(thermal_gap 0.5)
				(thermal_bridge_width 0.5)
				(island_removal_mode 0)
			)
			(polygon
				(pts
					(xy 57.77992 -82.8802) (xy 57.77992 -83.0326) (xy 57.17032 -83.0326) (xy 57.17032 -82.8802)
				)
			)
		)
	)
	(footprint ""
		(layer "F.Cu")
		(at 64.507618 -23.734522)
		(property "Reference" "MAC_PIN8"
			(at -3.936238 2.580132 0)
			(unlocked yes)
			(layer "F.SilkS")
			(effects
				(font
					(size 0.7874 0.5842)
					(thickness 0.1524)
				)
			)
		)
		(property "Value" ""
			(at 0 0 0)
			(layer "F.Fab")
			(effects
				(font
					(size 1.27 1.27)
				)
			)
		)
		(property "Device Type" "NUT-A200-00029-FB"
			(at 0 2.632964 0)
			(unlocked yes)
			(layer "F.Fab")
			(hide yes)
			(effects
				(font
					(size 0.7874 0.5842)
					(thickness 0.1524)
				)
			)
		)
		(property "User Part Number" "PARTNUM*"
			(at 0 3.826764 0)
			(unlocked yes)
			(layer "Cmts.User")
			(hide yes)
			(effects
				(font
					(size 0.7874 0.5842)
					(thickness 0.1524)
				)
			)
		)
		(duplicate_pad_numbers_are_jumpers no)
		(fp_circle
			(center 0 0)
			(end 1.524 0)
			(stroke
				(width 0.1)
				(type default)
			)
			(fill no)
			(layer "F.SilkS")
		)
		(fp_poly
			(pts
				(arc
					(start -1.260856 -0.1524)
					(mid -0.898049 -0.898049)
					(end -0.1524 -1.260856)
				)
				(arc
					(start -0.1524 -0.991616)
					(mid -0.709411 -0.709411)
					(end -0.991616 -0.1524)
				)
			)
			(stroke
				(width 0)
				(type default)
			)
			(fill yes)
			(layer "F.Paste")
		)
		(fp_poly
			(pts
				(arc
					(start -0.1524 1.260856)
					(mid -0.898049 0.898049)
					(end -1.260856 0.1524)
				)
				(arc
					(start -0.991616 0.1524)
					(mid -0.709411 0.709411)
					(end -0.1524 0.991616)
				)
			)
			(stroke
				(width 0)
				(type default)
			)
			(fill yes)
			(layer "F.Paste")
		)
		(fp_poly
			(pts
				(arc
					(start 0.1524 -1.260856)
					(mid 0.898049 -0.898049)
					(end 1.260856 -0.1524)
				)
				(arc
					(start 0.991616 -0.1524)
					(mid 0.709411 -0.709411)
					(end 0.1524 -0.991616)
				)
			)
			(stroke
				(width 0)
				(type default)
			)
			(fill yes)
			(layer "F.Paste")
		)
		(fp_poly
			(pts
				(arc
					(start 1.260856 0.1524)
					(mid 0.898049 0.898049)
					(end 0.1524 1.260856)
				)
				(arc
					(start 0.1524 0.991616)
					(mid 0.709411 0.709411)
					(end 0.991616 0.1524)
				)
			)
			(stroke
				(width 0)
				(type default)
			)
			(fill yes)
			(layer "F.Paste")
		)
		(fp_poly
			(pts
				(arc
					(start 6.35 0)
					(mid -6.35 0)
					(end 6.35 0)
				)
			)
			(stroke
				(width 0)
				(type default)
			)
			(fill no)
			(layer "B.CrtYd")
		)
		(fp_poly
			(pts
				(arc
					(start 1.778 0)
					(mid -1.778 0)
					(end 1.778 0)
				)
			)
			(stroke
				(width 0)
				(type default)
			)
			(fill no)
			(layer "F.CrtYd")
		)
		(fp_circle
			(center 0 0)
			(end 1.1684 0)
			(stroke
				(width 0.1)
				(type default)
			)
			(fill no)
			(layer "F.Fab")
		)
		(pad "1" thru_hole circle
			(at 0 0)
			(size 2.54 2.54)
			(drill 2.0066)
			(layers "*.Cu" "*.Mask")
			(remove_unused_layers no)
			(net "R_MAC_UART_RX_FPGA_TX")
			(thermal_gap 0.0254)
			(padstack
				(mode front_inner_back)
				(layer "Inner"
					(shape circle)
					(size 2.54 2.54)
					(clearance 0.0254)
				)
				(layer "B.Cu"
					(shape circle)
					(size 2.54 2.54)
				)
			)
		)
	)
	(footprint ""
		(layer "F.Cu")
		(at 146.431 -24.892)
		(property "Reference" "TP41"
			(at -0.7112 0.92837 0)
			(unlocked yes)
			(layer "F.SilkS")
			(effects
				(font
					(size 0.7874 0.5842)
					(thickness 0.1524)
				)
				(justify left)
			)
		)
		(property "Value" ""
			(at 0 0 0)
			(layer "F.Fab")
			(effects
				(font
					(size 1.27 1.27)
				)
			)
		)
		(property "Device Type" "TP_PIONT-TP010CT020B030_PTH-TPA"
			(at -1.341882 0.996696 0)
			(unlocked yes)
			(layer "F.Fab")
			(hide yes)
			(effects
				(font
					(size 0.7874 0.5842)
					(thickness 0.000001)
				)
				(justify left)
			)
		)
		(duplicate_pad_numbers_are_jumpers no)
		(fp_poly
			(pts
				(arc
					(start 0.889 0)
					(mid -0.889 0)
					(end 0.889 0)
				)
			)
			(stroke
				(width 0)
				(type default)
			)
			(fill no)
			(layer "B.CrtYd")
		)
		(fp_poly
			(pts
				(arc
					(start 0.889 0)
					(mid -0.889 0)
					(end 0.889 0)
				)
			)
			(stroke
				(width 0)
				(type default)
			)
			(fill no)
			(layer "F.CrtYd")
		)
		(pad "1" thru_hole circle
			(at 0 0)
			(size 0.508 0.508)
			(drill 0.254)
			(layers "*.Cu" "*.Mask")
			(remove_unused_layers no)
			(net "XP1R8V_FPGA_PG")
			(clearance 0.1016)
			(padstack
				(mode front_inner_back)
				(layer "Inner"
					(shape circle)
					(size 0.508 0.508)
					(clearance 0.1016)
				)
				(layer "B.Cu"
					(shape circle)
					(size 0.762 0.762)
					(clearance -0.0254)
				)
			)
		)
	)
	(footprint ""
		(layer "F.Cu")
		(at 110.236 -88.265 -90)
		(property "Reference" "R443"
			(at 2.794 -0.16637 90)
			(unlocked yes)
			(layer "F.SilkS")
			(effects
				(font
					(size 0.7874 0.5842)
					(thickness 0.1524)
				)
			)
		)
		(property "Value" "VAL*"
			(at 0.02032 2.13233 270)
			(unlocked yes)
			(layer "F.Fab")
			(hide yes)
			(effects
				(font
					(size 0.7874 0.5842)
					(thickness 0.1524)
				)
			)
		)
		(property "Tolerance" "TOL*"
			(at 0.044704 3.05435 270)
			(unlocked yes)
			(layer "Cmts.User")
			(hide yes)
			(effects
				(font
					(size 0.7874 0.5842)
					(thickness 0.1524)
				)
			)
		)
		(property "User Part Number" "PARTNUM*"
			(at 0.02032 4.024884 270)
			(unlocked yes)
			(layer "Cmts.User")
			(hide yes)
			(effects
				(font
					(size 0.7874 0.5842)
					(thickness 0.1524)
				)
			)
		)
		(property "Device Type" "RESISTOR-G155-11000-01,100OHM,A"
			(at 0.008382 1.210564 270)
			(unlocked yes)
			(layer "F.Fab")
			(hide yes)
			(effects
				(font
					(size 0.7874 0.5842)
					(thickness 0.1524)
				)
			)
		)
		(duplicate_pad_numbers_are_jumpers no)
		(fp_line
			(start -1.143 0.5588)
			(end 1.143 0.5588)
			(stroke
				(width 0.1)
				(type default)
			)
			(layer "F.SilkS")
		)
		(fp_line
			(start 1.143 0.5588)
			(end 1.143 -0.5588)
			(stroke
				(width 0.1)
				(type default)
			)
			(layer "F.SilkS")
		)
		(fp_line
			(start -1.143 -0.5588)
			(end -1.143 0.5588)
			(stroke
				(width 0.1)
				(type default)
			)
			(layer "F.SilkS")
		)
		(fp_line
			(start 1.143 -0.5588)
			(end -1.143 -0.5588)
			(stroke
				(width 0.1)
				(type default)
			)
			(layer "F.SilkS")
		)
		(fp_poly
			(pts
				(xy -1.143 0.5588) (xy 1.143 0.5588) (xy 1.143 -0.5588) (xy -1.143 -0.5588)
			)
			(stroke
				(width 0)
				(type default)
			)
			(fill no)
			(layer "F.CrtYd")
		)
		(fp_line
			(start -0.508 0.3048)
			(end 0.508 0.3048)
			(stroke
				(width 0.1)
				(type default)
			)
			(layer "F.Fab")
		)
		(fp_line
			(start 0.508 0.3048)
			(end 0.508 -0.3048)
			(stroke
				(width 0.1)
				(type default)
			)
			(layer "F.Fab")
		)
		(fp_line
			(start -0.508 -0.3048)
			(end -0.508 0.3048)
			(stroke
				(width 0.1)
				(type default)
			)
			(layer "F.Fab")
		)
		(fp_line
			(start 0.508 -0.3048)
			(end -0.508 -0.3048)
			(stroke
				(width 0.1)
				(type default)
			)
			(layer "F.Fab")
		)
		(pad "1" smd rect
			(at -0.5334 0 270)
			(size 0.7112 0.6096)
			(layers "F.Cu" "F.Mask" "F.Paste")
			(net "FT_USB_DETECT")
		)
		(pad "2" smd rect
			(at 0.5334 0 270)
			(size 0.7112 0.6096)
			(layers "F.Cu" "F.Mask" "F.Paste")
			(net "FPGA_IO_FT_USBDET_RST_N")
		)
		(zone
			(layer "F.Cu")
			(hatch none 0.5)
			(connect_pads
				(clearance 0)
			)
			(min_thickness 0.25)
			(keepout
				(tracks not_allowed)
				(vias allowed)
				(pads allowed)
				(copperpour not_allowed)
				(footprints allowed)
			)
			(placement
				(enabled no)
				(sheetname "")
			)
			(fill
				(thermal_gap 0.5)
				(thermal_bridge_width 0.5)
				(island_removal_mode 0)
			)
			(polygon
				(pts
					(xy 109.9312 -88.3412) (xy 109.9312 -88.1888) (xy 110.5408 -88.1888) (xy 110.5408 -88.3412)
				)
			)
		)
		(zone
			(layer "F.Cu")
			(hatch none 0.5)
			(connect_pads
				(clearance 0)
			)
			(min_thickness 0.25)
			(keepout
				(tracks allowed)
				(vias not_allowed)
				(pads allowed)
				(copperpour not_allowed)
				(footprints allowed)
			)
			(placement
				(enabled no)
				(sheetname "")
			)
			(fill
				(thermal_gap 0.5)
				(thermal_bridge_width 0.5)
				(island_removal_mode 0)
			)
			(polygon
				(pts
					(xy 109.9312 -88.3412) (xy 109.9312 -88.1888) (xy 110.5408 -88.1888) (xy 110.5408 -88.3412)
				)
			)
		)
	)
	(footprint ""
		(layer "F.Cu")
		(at 34.798 -129.667)
		(property "Reference" "SP23"
			(at 0 0 0)
			(layer "F.SilkS")
			(hide yes)
			(effects
				(font
					(size 1.27 1.27)
				)
			)
		)
		(property "Value" ""
			(at 0 0 0)
			(layer "F.Fab")
			(effects
				(font
					(size 1.27 1.27)
				)
			)
		)
		(duplicate_pad_numbers_are_jumpers no)
	)
)
